(kicad_pcb
	(version 20260206)
	(generator "pcbnew")
	(generator_version "10.0")
	(general
		(thickness 1.6)
		(legacy_teardrops no)
	)
	(paper "A4")
	(title_block
		(title "01162023_DA0F0TEBIF0_F0T_Expander_BD_F_brd_V02_OCP.brd")
		(comment 1 "Grand Teton / footprints 7215-7222 of 9728")
	)
	(layers
		(0 "F.Cu" signal "TOP")
		(4 "In1.Cu" signal "GND")
		(6 "In2.Cu" signal "VCC")
		(8 "In3.Cu" signal "VCC1")
		(10 "In4.Cu" signal "GND1")
		(12 "In5.Cu" signal "IN1")
		(14 "In6.Cu" signal "GND2")
		(16 "In7.Cu" signal "IN2")
		(18 "In8.Cu" signal "GND3")
		(20 "In9.Cu" signal "IN3")
		(22 "In10.Cu" signal "GND4")
		(24 "In11.Cu" signal "IN4")
		(26 "In12.Cu" signal "GND5")
		(28 "In13.Cu" signal "IN5")
		(30 "In14.Cu" signal "GND6")
		(32 "In15.Cu" signal "IN6")
		(34 "In16.Cu" signal "GND7")
		(2 "B.Cu" signal "BOTTOM")
		(9 "F.Adhes" user "F.Adhesive")
		(11 "B.Adhes" user "B.Adhesive")
		(13 "F.Paste" user "Package Geometry/Pastemask Top")
		(15 "B.Paste" user "Package Geometry/Pastemask Bottom")
		(5 "F.SilkS" user "Ref Des/Silkscreen Top")
		(7 "B.SilkS" user "Ref Des/Silkscreen Bottom")
		(1 "F.Mask" user "Board Geometry/Soldermask Top")
		(3 "B.Mask" user "Board Geometry/Soldermask Bottom")
		(17 "Dwgs.User" user "User.Drawings")
		(19 "Cmts.User" user "User.Comments")
		(21 "Eco1.User" user "User.Eco1")
		(23 "Eco2.User" user "User.Eco2")
		(25 "Edge.Cuts" user "Board Geometry/Outline")
		(27 "Margin" user)
		(31 "F.CrtYd" user "Package Geometry/Place Bound Top")
		(29 "B.CrtYd" user "Package Geometry/Place Bound Bottom")
		(35 "F.Fab" user "Ref Des/Assembly Top")
		(33 "B.Fab" user "Ref Des/Assembly Bottom")
	)
	(footprint ""
		(layer "B.Cu")
		(at 385.943602 -235.89996 180)
		(property "Reference" "C2581"
			(at 0 0 0)
			(layer "B.SilkS")
			(hide yes)
			(effects
				(font
					(size 1.27 1.27)
				)
				(justify mirror)
			)
		)
		(property "Value" ""
			(at 0 0 0)
			(layer "B.Fab")
			(effects
				(font
					(size 1.27 1.27)
				)
				(justify mirror)
			)
		)
		(duplicate_pad_numbers_are_jumpers no)
		(fp_line
			(start 1.2954 0.5842)
			(end 1.2954 -0.5842)
			(stroke
				(width 0.1524)
				(type default)
			)
			(layer "B.SilkS")
		)
		(fp_line
			(start 1.2954 -0.5842)
			(end -1.2954 -0.5842)
			(stroke
				(width 0.1524)
				(type default)
			)
			(layer "B.SilkS")
		)
		(fp_line
			(start -1.2954 0.5842)
			(end 1.2954 0.5842)
			(stroke
				(width 0.1524)
				(type default)
			)
			(layer "B.SilkS")
		)
		(fp_line
			(start -1.2954 -0.5842)
			(end -1.2954 0.5842)
			(stroke
				(width 0.1524)
				(type default)
			)
			(layer "B.SilkS")
		)
		(fp_line
			(start 1.1938 0.4064)
			(end 1.1938 -0.4064)
			(stroke
				(width 0.1)
				(type default)
			)
			(layer "B.Fab")
		)
		(fp_line
			(start 1.1938 -0.4064)
			(end 0.8636 -0.4064)
			(stroke
				(width 0.1)
				(type default)
			)
			(layer "B.Fab")
		)
		(fp_line
			(start 0.8636 0.4572)
			(end 0.8636 0.4064)
			(stroke
				(width 0.1)
				(type default)
			)
			(layer "B.Fab")
		)
		(fp_line
			(start 0.8636 0.4064)
			(end 1.1938 0.4064)
			(stroke
				(width 0.1)
				(type default)
			)
			(layer "B.Fab")
		)
		(fp_line
			(start 0.8636 -0.4064)
			(end 0.8636 -0.4572)
			(stroke
				(width 0.1)
				(type default)
			)
			(layer "B.Fab")
		)
		(fp_line
			(start 0.8636 -0.4572)
			(end -0.8636 -0.4572)
			(stroke
				(width 0.1)
				(type default)
			)
			(layer "B.Fab")
		)
		(fp_line
			(start -0.8636 0.4572)
			(end 0.8636 0.4572)
			(stroke
				(width 0.1)
				(type default)
			)
			(layer "B.Fab")
		)
		(fp_line
			(start -0.8636 0.4064)
			(end -0.8636 0.4572)
			(stroke
				(width 0.1)
				(type default)
			)
			(layer "B.Fab")
		)
		(fp_line
			(start -0.8636 -0.4064)
			(end -1.1938 -0.4064)
			(stroke
				(width 0.1)
				(type default)
			)
			(layer "B.Fab")
		)
		(fp_line
			(start -0.8636 -0.4572)
			(end -0.8636 -0.4064)
			(stroke
				(width 0.1)
				(type default)
			)
			(layer "B.Fab")
		)
		(fp_line
			(start -1.1938 0.4064)
			(end -0.8636 0.4064)
			(stroke
				(width 0.1)
				(type default)
			)
			(layer "B.Fab")
		)
		(fp_line
			(start -1.1938 -0.4064)
			(end -1.1938 0.4064)
			(stroke
				(width 0.1)
				(type default)
			)
			(layer "B.Fab")
		)
		(pad "1" smd rect
			(at 0.7366 0 90)
			(size 0.7112 0.8128)
			(layers "B.Cu" "B.Mask" "B.Paste")
			(net "P3V3_SDB_VPLL")
		)
		(pad "2" smd rect
			(at -0.7366 0 90)
			(size 0.7112 0.8128)
			(layers "B.Cu" "B.Mask" "B.Paste")
			(net "GND")
		)
	)
	(footprint ""
		(layer "B.Cu")
		(at 132.826506 -321.834764 -90)
		(property "Reference" "R6487"
			(at 0 0 90)
			(layer "B.SilkS")
			(hide yes)
			(effects
				(font
					(size 1.27 1.27)
				)
				(justify mirror)
			)
		)
		(property "Value" ""
			(at 0 0 90)
			(layer "B.Fab")
			(effects
				(font
					(size 1.27 1.27)
				)
				(justify mirror)
			)
		)
		(duplicate_pad_numbers_are_jumpers no)
		(fp_line
			(start -0.7874 0.4064)
			(end 0.7874 0.4064)
			(stroke
				(width 0.1524)
				(type default)
			)
			(layer "B.SilkS")
		)
		(fp_line
			(start 0.7874 0.4064)
			(end 0.7874 -0.4064)
			(stroke
				(width 0.1524)
				(type default)
			)
			(layer "B.SilkS")
		)
		(fp_line
			(start -0.7874 -0.4064)
			(end -0.7874 0.4064)
			(stroke
				(width 0.1524)
				(type default)
			)
			(layer "B.SilkS")
		)
		(fp_line
			(start 0.7874 -0.4064)
			(end -0.7874 -0.4064)
			(stroke
				(width 0.1524)
				(type default)
			)
			(layer "B.SilkS")
		)
		(fp_line
			(start -0.67945 0.3048)
			(end -0.120396 0.3048)
			(stroke
				(width 0.1)
				(type default)
			)
			(layer "B.Fab")
		)
		(fp_line
			(start -0.120396 0.3048)
			(end -0.120396 0.2794)
			(stroke
				(width 0.1)
				(type default)
			)
			(layer "B.Fab")
		)
		(fp_line
			(start 0.12065 0.3048)
			(end 0.67945 0.3048)
			(stroke
				(width 0.1)
				(type default)
			)
			(layer "B.Fab")
		)
		(fp_line
			(start 0.67945 0.3048)
			(end 0.67945 -0.305054)
			(stroke
				(width 0.1)
				(type default)
			)
			(layer "B.Fab")
		)
		(fp_line
			(start -0.120396 0.2794)
			(end 0.12065 0.2794)
			(stroke
				(width 0.1)
				(type default)
			)
			(layer "B.Fab")
		)
		(fp_line
			(start 0.12065 0.2794)
			(end 0.12065 0.3048)
			(stroke
				(width 0.1)
				(type default)
			)
			(layer "B.Fab")
		)
		(fp_line
			(start -0.12065 -0.2794)
			(end -0.12065 -0.3048)
			(stroke
				(width 0.1)
				(type default)
			)
			(layer "B.Fab")
		)
		(fp_line
			(start 0.12065 -0.2794)
			(end -0.12065 -0.2794)
			(stroke
				(width 0.1)
				(type default)
			)
			(layer "B.Fab")
		)
		(fp_line
			(start -0.67945 -0.3048)
			(end -0.67945 0.3048)
			(stroke
				(width 0.1)
				(type default)
			)
			(layer "B.Fab")
		)
		(fp_line
			(start -0.12065 -0.3048)
			(end -0.67945 -0.3048)
			(stroke
				(width 0.1)
				(type default)
			)
			(layer "B.Fab")
		)
		(fp_line
			(start 0.12065 -0.305054)
			(end 0.12065 -0.2794)
			(stroke
				(width 0.1)
				(type default)
			)
			(layer "B.Fab")
		)
		(fp_line
			(start 0.67945 -0.305054)
			(end 0.12065 -0.305054)
			(stroke
				(width 0.1)
				(type default)
			)
			(layer "B.Fab")
		)
		(pad "1" smd circle
			(at 0.40005 0 90)
			(size 0 0)
			(layers "B.Cu" "B.Mask" "B.Paste")
			(net "P0V8_SERDES_VDDA_PEX1")
		)
		(pad "2" smd circle
			(at -0.40005 0 90)
			(size 0 0)
			(layers "B.Cu" "B.Mask" "B.Paste")
			(net "P0V8_SERDES_VDDA_PEX1_C10")
		)
	)
	(footprint ""
		(layer "B.Cu")
		(at 51.099974 -299.699934 -90)
		(property "Reference" "C1177"
			(at 0 0 90)
			(layer "B.SilkS")
			(hide yes)
			(effects
				(font
					(size 1.27 1.27)
				)
				(justify mirror)
			)
		)
		(property "Value" ""
			(at 0 0 90)
			(layer "B.Fab")
			(effects
				(font
					(size 1.27 1.27)
				)
				(justify mirror)
			)
		)
		(duplicate_pad_numbers_are_jumpers no)
		(fp_line
			(start -0.299974 0.150114)
			(end 0.299974 0.150114)
			(stroke
				(width 0.1)
				(type default)
			)
			(layer "B.Fab")
		)
		(fp_line
			(start 0.299974 0.150114)
			(end 0.299974 -0.150114)
			(stroke
				(width 0.1)
				(type default)
			)
			(layer "B.Fab")
		)
		(fp_line
			(start -0.299974 -0.150114)
			(end -0.299974 0.150114)
			(stroke
				(width 0.1)
				(type default)
			)
			(layer "B.Fab")
		)
		(fp_line
			(start 0.299974 -0.150114)
			(end -0.299974 -0.150114)
			(stroke
				(width 0.1)
				(type default)
			)
			(layer "B.Fab")
		)
		(pad "1" smd rect
			(at 0.2667 0 90)
			(size 0.3048 0.381)
			(layers "B.Cu" "B.Mask" "B.Paste")
			(net "P0V8_SERDES_VDDA_PEX0")
		)
		(pad "2" smd rect
			(at -0.2667 0 90)
			(size 0.3048 0.381)
			(layers "B.Cu" "B.Mask" "B.Paste")
			(net "GND")
		)
	)
	(footprint ""
		(layer "B.Cu")
		(at 15.748762 -385.723384 180)
		(property "Reference" "C4473"
			(at 0 0 0)
			(layer "B.SilkS")
			(hide yes)
			(effects
				(font
					(size 1.27 1.27)
				)
				(justify mirror)
			)
		)
		(property "Value" ""
			(at 0 0 0)
			(layer "B.Fab")
			(effects
				(font
					(size 1.27 1.27)
				)
				(justify mirror)
			)
		)
		(duplicate_pad_numbers_are_jumpers no)
		(fp_line
			(start 0.7874 0.4064)
			(end 0.7874 -0.4064)
			(stroke
				(width 0.1524)
				(type default)
			)
			(layer "B.SilkS")
		)
		(fp_line
			(start 0.7874 -0.4064)
			(end -0.7874 -0.4064)
			(stroke
				(width 0.1524)
				(type default)
			)
			(layer "B.SilkS")
		)
		(fp_line
			(start -0.7874 0.4064)
			(end 0.7874 0.4064)
			(stroke
				(width 0.1524)
				(type default)
			)
			(layer "B.SilkS")
		)
		(fp_line
			(start -0.7874 -0.4064)
			(end -0.7874 0.4064)
			(stroke
				(width 0.1524)
				(type default)
			)
			(layer "B.SilkS")
		)
		(fp_line
			(start 0.67945 0.3048)
			(end 0.67945 -0.305054)
			(stroke
				(width 0.1)
				(type default)
			)
			(layer "B.Fab")
		)
		(fp_line
			(start 0.67945 -0.305054)
			(end 0.12065 -0.305054)
			(stroke
				(width 0.1)
				(type default)
			)
			(layer "B.Fab")
		)
		(fp_line
			(start 0.12065 0.3048)
			(end 0.67945 0.3048)
			(stroke
				(width 0.1)
				(type default)
			)
			(layer "B.Fab")
		)
		(fp_line
			(start 0.12065 0.2794)
			(end 0.12065 0.3048)
			(stroke
				(width 0.1)
				(type default)
			)
			(layer "B.Fab")
		)
		(fp_line
			(start 0.12065 -0.2794)
			(end -0.12065 -0.2794)
			(stroke
				(width 0.1)
				(type default)
			)
			(layer "B.Fab")
		)
		(fp_line
			(start 0.12065 -0.305054)
			(end 0.12065 -0.2794)
			(stroke
				(width 0.1)
				(type default)
			)
			(layer "B.Fab")
		)
		(fp_line
			(start -0.120396 0.3048)
			(end -0.120396 0.2794)
			(stroke
				(width 0.1)
				(type default)
			)
			(layer "B.Fab")
		)
		(fp_line
			(start -0.120396 0.2794)
			(end 0.12065 0.2794)
			(stroke
				(width 0.1)
				(type default)
			)
			(layer "B.Fab")
		)
		(fp_line
			(start -0.12065 -0.2794)
			(end -0.12065 -0.3048)
			(stroke
				(width 0.1)
				(type default)
			)
			(layer "B.Fab")
		)
		(fp_line
			(start -0.12065 -0.3048)
			(end -0.67945 -0.3048)
			(stroke
				(width 0.1)
				(type default)
			)
			(layer "B.Fab")
		)
		(fp_line
			(start -0.67945 0.3048)
			(end -0.120396 0.3048)
			(stroke
				(width 0.1)
				(type default)
			)
			(layer "B.Fab")
		)
		(fp_line
			(start -0.67945 -0.3048)
			(end -0.67945 0.3048)
			(stroke
				(width 0.1)
				(type default)
			)
			(layer "B.Fab")
		)
		(pad "1" smd circle
			(at 0.40005 0)
			(size 0 0)
			(layers "B.Cu" "B.Mask" "B.Paste")
			(net "P1V2_USB_8042")
		)
		(pad "2" smd circle
			(at -0.40005 0)
			(size 0 0)
			(layers "B.Cu" "B.Mask" "B.Paste")
			(net "GND")
		)
	)
	(footprint ""
		(layer "B.Cu")
		(at 288.99993 -301.599854 -90)
		(property "Reference" "C1736"
			(at 0 0 90)
			(layer "B.SilkS")
			(hide yes)
			(effects
				(font
					(size 1.27 1.27)
				)
				(justify mirror)
			)
		)
		(property "Value" ""
			(at 0 0 90)
			(layer "B.Fab")
			(effects
				(font
					(size 1.27 1.27)
				)
				(justify mirror)
			)
		)
		(duplicate_pad_numbers_are_jumpers no)
		(fp_line
			(start -0.299974 0.150114)
			(end 0.299974 0.150114)
			(stroke
				(width 0.1)
				(type default)
			)
			(layer "B.Fab")
		)
		(fp_line
			(start 0.299974 0.150114)
			(end 0.299974 -0.150114)
			(stroke
				(width 0.1)
				(type default)
			)
			(layer "B.Fab")
		)
		(fp_line
			(start -0.299974 -0.150114)
			(end -0.299974 0.150114)
			(stroke
				(width 0.1)
				(type default)
			)
			(layer "B.Fab")
		)
		(fp_line
			(start 0.299974 -0.150114)
			(end -0.299974 -0.150114)
			(stroke
				(width 0.1)
				(type default)
			)
			(layer "B.Fab")
		)
		(pad "1" smd rect
			(at 0.2667 0 90)
			(size 0.3048 0.381)
			(layers "B.Cu" "B.Mask" "B.Paste")
			(net "P0V8_SERDES_VDDA_PEX2")
		)
		(pad "2" smd rect
			(at -0.2667 0 90)
			(size 0.3048 0.381)
			(layers "B.Cu" "B.Mask" "B.Paste")
			(net "GND")
		)
	)
	(footprint ""
		(layer "B.Cu")
		(at 227.190046 -153.000202 -90)
		(property "Reference" "C2803"
			(at 0 0 90)
			(layer "B.SilkS")
			(hide yes)
			(effects
				(font
					(size 1.27 1.27)
				)
				(justify mirror)
			)
		)
		(property "Value" ""
			(at 0 0 90)
			(layer "B.Fab")
			(effects
				(font
					(size 1.27 1.27)
				)
				(justify mirror)
			)
		)
		(duplicate_pad_numbers_are_jumpers no)
		(fp_line
			(start -0.7874 0.4064)
			(end 0.7874 0.4064)
			(stroke
				(width 0.1524)
				(type default)
			)
			(layer "B.SilkS")
		)
		(fp_line
			(start 0.7874 0.4064)
			(end 0.7874 -0.4064)
			(stroke
				(width 0.1524)
				(type default)
			)
			(layer "B.SilkS")
		)
		(fp_line
			(start -0.7874 -0.4064)
			(end -0.7874 0.4064)
			(stroke
				(width 0.1524)
				(type default)
			)
			(layer "B.SilkS")
		)
		(fp_line
			(start 0.7874 -0.4064)
			(end -0.7874 -0.4064)
			(stroke
				(width 0.1524)
				(type default)
			)
			(layer "B.SilkS")
		)
		(fp_line
			(start -0.67945 0.3048)
			(end -0.120396 0.3048)
			(stroke
				(width 0.1)
				(type default)
			)
			(layer "B.Fab")
		)
		(fp_line
			(start -0.120396 0.3048)
			(end -0.120396 0.2794)
			(stroke
				(width 0.1)
				(type default)
			)
			(layer "B.Fab")
		)
		(fp_line
			(start 0.12065 0.3048)
			(end 0.67945 0.3048)
			(stroke
				(width 0.1)
				(type default)
			)
			(layer "B.Fab")
		)
		(fp_line
			(start 0.67945 0.3048)
			(end 0.67945 -0.305054)
			(stroke
				(width 0.1)
				(type default)
			)
			(layer "B.Fab")
		)
		(fp_line
			(start -0.120396 0.2794)
			(end 0.12065 0.2794)
			(stroke
				(width 0.1)
				(type default)
			)
			(layer "B.Fab")
		)
		(fp_line
			(start 0.12065 0.2794)
			(end 0.12065 0.3048)
			(stroke
				(width 0.1)
				(type default)
			)
			(layer "B.Fab")
		)
		(fp_line
			(start -0.12065 -0.2794)
			(end -0.12065 -0.3048)
			(stroke
				(width 0.1)
				(type default)
			)
			(layer "B.Fab")
		)
		(fp_line
			(start 0.12065 -0.2794)
			(end -0.12065 -0.2794)
			(stroke
				(width 0.1)
				(type default)
			)
			(layer "B.Fab")
		)
		(fp_line
			(start -0.67945 -0.3048)
			(end -0.67945 0.3048)
			(stroke
				(width 0.1)
				(type default)
			)
			(layer "B.Fab")
		)
		(fp_line
			(start -0.12065 -0.3048)
			(end -0.67945 -0.3048)
			(stroke
				(width 0.1)
				(type default)
			)
			(layer "B.Fab")
		)
		(fp_line
			(start 0.12065 -0.305054)
			(end 0.12065 -0.2794)
			(stroke
				(width 0.1)
				(type default)
			)
			(layer "B.Fab")
		)
		(fp_line
			(start 0.67945 -0.305054)
			(end 0.12065 -0.305054)
			(stroke
				(width 0.1)
				(type default)
			)
			(layer "B.Fab")
		)
		(pad "1" smd circle
			(at 0.40005 0 90)
			(size 0 0)
			(layers "B.Cu" "B.Mask" "B.Paste")
			(net "P3V3_CLK_GEN_VDDMXCK_CK440_PEX")
		)
		(pad "2" smd circle
			(at -0.40005 0 90)
			(size 0 0)
			(layers "B.Cu" "B.Mask" "B.Paste")
			(net "GND")
		)
	)
	(footprint ""
		(layer "B.Cu")
		(at 333.073756 -329.008994 180)
		(property "Reference" "PJ23"
			(at 0 0 0)
			(layer "B.SilkS")
			(hide yes)
			(effects
				(font
					(size 1.27 1.27)
				)
				(justify mirror)
			)
		)
		(property "Value" ""
			(at 0 0 0)
			(layer "B.Fab")
			(effects
				(font
					(size 1.27 1.27)
				)
				(justify mirror)
			)
		)
		(duplicate_pad_numbers_are_jumpers no)
		(pad "1" smd circle
			(at 0.40005 0 270)
			(size 0 0)
			(layers "B.Cu" "B.Mask" "B.Paste")
			(net "VSENSE_P0V8_PEX2_SKT_VRTN")
		)
		(pad "2" smd rect
			(at -0.40005 0 180)
			(size 0.4572 0.508)
			(layers "B.Cu" "B.Mask" "B.Paste")
			(net "SH_P0V8_PEX2_RGND2")
		)
		(zone
			(layer "B.Cu")
			(hatch none 0.5)
			(connect_pads
				(clearance 0)
			)
			(min_thickness 0.25)
			(keepout
				(tracks allowed)
				(vias not_allowed)
				(pads allowed)
				(copperpour not_allowed)
				(footprints allowed)
			)
			(placement
				(enabled no)
				(sheetname "")
			)
			(fill
				(thermal_gap 0.5)
				(thermal_bridge_width 0.5)
				(island_removal_mode 0)
			)
			(polygon
				(pts
					(xy 333.759556 -329.313794) (xy 333.759556 -328.704194) (xy 332.387956 -328.704194) (xy 332.387956 -329.313794)
				)
			)
		)
	)
	(footprint ""
		(layer "B.Cu")
		(at 228.418644 -231.225598 -90)
		(property "Reference" "R4551"
			(at 0 0 90)
			(layer "B.SilkS")
			(hide yes)
			(effects
				(font
					(size 1.27 1.27)
				)
				(justify mirror)
			)
		)
		(property "Value" ""
			(at 0 0 90)
			(layer "B.Fab")
			(effects
				(font
					(size 1.27 1.27)
				)
				(justify mirror)
			)
		)
		(duplicate_pad_numbers_are_jumpers no)
		(fp_line
			(start -0.7874 0.4064)
			(end 0.7874 0.4064)
			(stroke
				(width 0.1524)
				(type default)
			)
			(layer "B.SilkS")
		)
		(fp_line
			(start 0.7874 0.4064)
			(end 0.7874 -0.4064)
			(stroke
				(width 0.1524)
				(type default)
			)
			(layer "B.SilkS")
		)
		(fp_line
			(start -0.7874 -0.4064)
			(end -0.7874 0.4064)
			(stroke
				(width 0.1524)
				(type default)
			)
			(layer "B.SilkS")
		)
		(fp_line
			(start 0.7874 -0.4064)
			(end -0.7874 -0.4064)
			(stroke
				(width 0.1524)
				(type default)
			)
			(layer "B.SilkS")
		)
		(fp_line
			(start -0.67945 0.3048)
			(end -0.120396 0.3048)
			(stroke
				(width 0.1)
				(type default)
			)
			(layer "B.Fab")
		)
		(fp_line
			(start -0.120396 0.3048)
			(end -0.120396 0.2794)
			(stroke
				(width 0.1)
				(type default)
			)
			(layer "B.Fab")
		)
		(fp_line
			(start 0.12065 0.3048)
			(end 0.67945 0.3048)
			(stroke
				(width 0.1)
				(type default)
			)
			(layer "B.Fab")
		)
		(fp_line
			(start 0.67945 0.3048)
			(end 0.67945 -0.305054)
			(stroke
				(width 0.1)
				(type default)
			)
			(layer "B.Fab")
		)
		(fp_line
			(start -0.120396 0.2794)
			(end 0.12065 0.2794)
			(stroke
				(width 0.1)
				(type default)
			)
			(layer "B.Fab")
		)
		(fp_line
			(start 0.12065 0.2794)
			(end 0.12065 0.3048)
			(stroke
				(width 0.1)
				(type default)
			)
			(layer "B.Fab")
		)
		(fp_line
			(start -0.12065 -0.2794)
			(end -0.12065 -0.3048)
			(stroke
				(width 0.1)
				(type default)
			)
			(layer "B.Fab")
		)
		(fp_line
			(start 0.12065 -0.2794)
			(end -0.12065 -0.2794)
			(stroke
				(width 0.1)
				(type default)
			)
			(layer "B.Fab")
		)
		(fp_line
			(start -0.67945 -0.3048)
			(end -0.67945 0.3048)
			(stroke
				(width 0.1)
				(type default)
			)
			(layer "B.Fab")
		)
		(fp_line
			(start -0.12065 -0.3048)
			(end -0.67945 -0.3048)
			(stroke
				(width 0.1)
				(type default)
			)
			(layer "B.Fab")
		)
		(fp_line
			(start 0.12065 -0.305054)
			(end 0.12065 -0.2794)
			(stroke
				(width 0.1)
				(type default)
			)
			(layer "B.Fab")
		)
		(fp_line
			(start 0.67945 -0.305054)
			(end 0.12065 -0.305054)
			(stroke
				(width 0.1)
				(type default)
			)
			(layer "B.Fab")
		)
		(pad "1" smd circle
			(at 0.40005 0 90)
			(size 0 0)
			(layers "B.Cu" "B.Mask" "B.Paste")
			(net "BOARD_ID1")
		)
		(pad "2" smd circle
			(at -0.40005 0 90)
			(size 0 0)
			(layers "B.Cu" "B.Mask" "B.Paste")
			(net "P3V3_AUX")
		)
	)
)
